(kicad_pcb
	(version 20260206)
	(generator "pcbnew")
	(generator_version "10.0")
	(general
		(thickness 1.6)
		(legacy_teardrops no)
	)
	(paper "A4")
	(title_block
		(title "12092022_DA0F0TFB6D0_F0T_FAN_BOARD_MP5048_D_brd_v02_OCP.brd")
		(comment 1 "Grand Teton / footprints 179-184 of 924")
	)
	(layers
		(0 "F.Cu" signal "TOP")
		(4 "In1.Cu" signal "GND")
		(6 "In2.Cu" signal "IN1")
		(8 "In3.Cu" signal "IN2")
		(10 "In4.Cu" signal "GND1")
		(2 "B.Cu" signal "BOTTOM")
		(9 "F.Adhes" user "F.Adhesive")
		(11 "B.Adhes" user "B.Adhesive")
		(13 "F.Paste" user "Package Geometry/Pastemask Top")
		(15 "B.Paste" user "Package Geometry/Pastemask Bottom")
		(5 "F.SilkS" user "Ref Des/Silkscreen Top")
		(7 "B.SilkS" user "Ref Des/Silkscreen Bottom")
		(1 "F.Mask" user "Board Geometry/Soldermask Top")
		(3 "B.Mask" user "Board Geometry/Soldermask Bottom")
		(17 "Dwgs.User" user "User.Drawings")
		(19 "Cmts.User" user "User.Comments")
		(21 "Eco1.User" user "User.Eco1")
		(23 "Eco2.User" user "User.Eco2")
		(25 "Edge.Cuts" user "Board Geometry/Outline")
		(27 "Margin" user)
		(31 "F.CrtYd" user "Package Geometry/Place Bound Top")
		(29 "B.CrtYd" user "Package Geometry/Place Bound Bottom")
		(35 "F.Fab" user "Ref Des/Assembly Top")
		(33 "B.Fab" user "Ref Des/Assembly Bottom")
	)
	(footprint ""
		(layer "F.Cu")
		(at 33.02 -121.92 90)
		(property "Reference" "R4781"
			(at 0 0 90)
			(layer "F.SilkS")
			(hide yes)
			(effects
				(font
					(size 1.27 1.27)
				)
			)
		)
		(property "Value" ""
			(at 0 0 90)
			(layer "F.Fab")
			(effects
				(font
					(size 1.27 1.27)
				)
			)
		)
		(duplicate_pad_numbers_are_jumpers no)
		(fp_line
			(start 0.7874 -0.4064)
			(end 0.7874 0.4064)
			(stroke
				(width 0.1524)
				(type default)
			)
			(layer "F.SilkS")
		)
		(fp_line
			(start -0.7874 -0.4064)
			(end 0.7874 -0.4064)
			(stroke
				(width 0.1524)
				(type default)
			)
			(layer "F.SilkS")
		)
		(fp_line
			(start 0.7874 0.4064)
			(end -0.7874 0.4064)
			(stroke
				(width 0.1524)
				(type default)
			)
			(layer "F.SilkS")
		)
		(fp_line
			(start -0.7874 0.4064)
			(end -0.7874 -0.4064)
			(stroke
				(width 0.1524)
				(type default)
			)
			(layer "F.SilkS")
		)
		(fp_line
			(start -0.12065 -0.305054)
			(end -0.12065 -0.2794)
			(stroke
				(width 0.1)
				(type default)
			)
			(layer "F.Fab")
		)
		(fp_line
			(start -0.67945 -0.305054)
			(end -0.12065 -0.305054)
			(stroke
				(width 0.1)
				(type default)
			)
			(layer "F.Fab")
		)
		(fp_line
			(start 0.67945 -0.3048)
			(end 0.67945 0.3048)
			(stroke
				(width 0.1)
				(type default)
			)
			(layer "F.Fab")
		)
		(fp_line
			(start 0.12065 -0.3048)
			(end 0.67945 -0.3048)
			(stroke
				(width 0.1)
				(type default)
			)
			(layer "F.Fab")
		)
		(fp_line
			(start 0.12065 -0.2794)
			(end 0.12065 -0.3048)
			(stroke
				(width 0.1)
				(type default)
			)
			(layer "F.Fab")
		)
		(fp_line
			(start -0.12065 -0.2794)
			(end 0.12065 -0.2794)
			(stroke
				(width 0.1)
				(type default)
			)
			(layer "F.Fab")
		)
		(fp_line
			(start 0.120396 0.2794)
			(end -0.12065 0.2794)
			(stroke
				(width 0.1)
				(type default)
			)
			(layer "F.Fab")
		)
		(fp_line
			(start -0.12065 0.2794)
			(end -0.12065 0.3048)
			(stroke
				(width 0.1)
				(type default)
			)
			(layer "F.Fab")
		)
		(fp_line
			(start 0.67945 0.3048)
			(end 0.120396 0.3048)
			(stroke
				(width 0.1)
				(type default)
			)
			(layer "F.Fab")
		)
		(fp_line
			(start 0.120396 0.3048)
			(end 0.120396 0.2794)
			(stroke
				(width 0.1)
				(type default)
			)
			(layer "F.Fab")
		)
		(fp_line
			(start -0.12065 0.3048)
			(end -0.67945 0.3048)
			(stroke
				(width 0.1)
				(type default)
			)
			(layer "F.Fab")
		)
		(fp_line
			(start -0.67945 0.3048)
			(end -0.67945 -0.305054)
			(stroke
				(width 0.1)
				(type default)
			)
			(layer "F.Fab")
		)
		(pad "1" smd circle
			(at -0.40005 0 90)
			(size 0 0)
			(layers "F.Cu" "F.Mask" "F.Paste")
			(net "GND")
		)
		(pad "2" smd circle
			(at 0.40005 0 90)
			(size 0 0)
			(layers "F.Cu" "F.Mask" "F.Paste")
			(net "MAX31790_U317_ADD0")
		)
	)
	(footprint ""
		(layer "F.Cu")
		(at 30.353 -185.674)
		(property "Reference" "R4957"
			(at 0 0 0)
			(layer "F.SilkS")
			(hide yes)
			(effects
				(font
					(size 1.27 1.27)
				)
			)
		)
		(property "Value" ""
			(at 0 0 0)
			(layer "F.Fab")
			(effects
				(font
					(size 1.27 1.27)
				)
			)
		)
		(duplicate_pad_numbers_are_jumpers no)
		(fp_line
			(start -0.7874 -0.4064)
			(end 0.7874 -0.4064)
			(stroke
				(width 0.1524)
				(type default)
			)
			(layer "F.SilkS")
		)
		(fp_line
			(start -0.7874 0.4064)
			(end -0.7874 -0.4064)
			(stroke
				(width 0.1524)
				(type default)
			)
			(layer "F.SilkS")
		)
		(fp_line
			(start 0.7874 -0.4064)
			(end 0.7874 0.4064)
			(stroke
				(width 0.1524)
				(type default)
			)
			(layer "F.SilkS")
		)
		(fp_line
			(start 0.7874 0.4064)
			(end -0.7874 0.4064)
			(stroke
				(width 0.1524)
				(type default)
			)
			(layer "F.SilkS")
		)
		(fp_line
			(start -0.67945 -0.305054)
			(end -0.12065 -0.305054)
			(stroke
				(width 0.1)
				(type default)
			)
			(layer "F.Fab")
		)
		(fp_line
			(start -0.67945 0.3048)
			(end -0.67945 -0.305054)
			(stroke
				(width 0.1)
				(type default)
			)
			(layer "F.Fab")
		)
		(fp_line
			(start -0.12065 -0.305054)
			(end -0.12065 -0.2794)
			(stroke
				(width 0.1)
				(type default)
			)
			(layer "F.Fab")
		)
		(fp_line
			(start -0.12065 -0.2794)
			(end 0.12065 -0.2794)
			(stroke
				(width 0.1)
				(type default)
			)
			(layer "F.Fab")
		)
		(fp_line
			(start -0.12065 0.2794)
			(end -0.12065 0.3048)
			(stroke
				(width 0.1)
				(type default)
			)
			(layer "F.Fab")
		)
		(fp_line
			(start -0.12065 0.3048)
			(end -0.67945 0.3048)
			(stroke
				(width 0.1)
				(type default)
			)
			(layer "F.Fab")
		)
		(fp_line
			(start 0.120396 0.2794)
			(end -0.12065 0.2794)
			(stroke
				(width 0.1)
				(type default)
			)
			(layer "F.Fab")
		)
		(fp_line
			(start 0.120396 0.3048)
			(end 0.120396 0.2794)
			(stroke
				(width 0.1)
				(type default)
			)
			(layer "F.Fab")
		)
		(fp_line
			(start 0.12065 -0.3048)
			(end 0.67945 -0.3048)
			(stroke
				(width 0.1)
				(type default)
			)
			(layer "F.Fab")
		)
		(fp_line
			(start 0.12065 -0.2794)
			(end 0.12065 -0.3048)
			(stroke
				(width 0.1)
				(type default)
			)
			(layer "F.Fab")
		)
		(fp_line
			(start 0.67945 -0.3048)
			(end 0.67945 0.3048)
			(stroke
				(width 0.1)
				(type default)
			)
			(layer "F.Fab")
		)
		(fp_line
			(start 0.67945 0.3048)
			(end 0.120396 0.3048)
			(stroke
				(width 0.1)
				(type default)
			)
			(layer "F.Fab")
		)
		(pad "1" smd circle
			(at -0.40005 0)
			(size 0 0)
			(layers "F.Cu" "F.Mask" "F.Paste")
			(net "P3V3_AUX")
		)
		(pad "2" smd circle
			(at 0.40005 0)
			(size 0 0)
			(layers "F.Cu" "F.Mask" "F.Paste")
			(net "P52V_FAN_6_BUFF_EN")
		)
	)
	(footprint ""
		(layer "F.Cu")
		(at 37.211 -203.581)
		(property "Reference" "D269"
			(at 1.27 1.04267 0)
			(unlocked yes)
			(layer "F.SilkS")
			(effects
				(font
					(size 0.7874 0.5842)
					(thickness 0.1524)
				)
				(justify left)
			)
		)
		(property "Value" ""
			(at 0 0 0)
			(layer "F.Fab")
			(effects
				(font
					(size 1.27 1.27)
				)
			)
		)
		(duplicate_pad_numbers_are_jumpers no)
		(fp_line
			(start -0.854964 -0.450088)
			(end -0.854964 0.450088)
			(stroke
				(width 0.1524)
				(type default)
			)
			(layer "F.SilkS")
		)
		(fp_line
			(start -0.854964 0.450088)
			(end 0.925068 0.450088)
			(stroke
				(width 0.1524)
				(type default)
			)
			(layer "F.SilkS")
		)
		(fp_line
			(start 0.845058 0.4064)
			(end 0.845058 -0.381)
			(stroke
				(width 0.1524)
				(type default)
			)
			(layer "F.SilkS")
		)
		(fp_line
			(start 0.870458 -0.2794)
			(end 0.845058 0.4064)
			(stroke
				(width 0.1524)
				(type default)
			)
			(layer "F.SilkS")
		)
		(fp_line
			(start 0.94488 -0.450088)
			(end -0.854964 -0.450088)
			(stroke
				(width 0.1524)
				(type default)
			)
			(layer "F.SilkS")
		)
		(fp_line
			(start 0.94488 0.450088)
			(end 0.94488 -0.450088)
			(stroke
				(width 0.1524)
				(type default)
			)
			(layer "F.SilkS")
		)
		(fp_line
			(start -0.54991 -0.350012)
			(end -0.54991 0.350012)
			(stroke
				(width 0.1)
				(type default)
			)
			(layer "F.Fab")
		)
		(fp_line
			(start -0.54991 0.350012)
			(end 0.54991 0.350012)
			(stroke
				(width 0.1)
				(type default)
			)
			(layer "F.Fab")
		)
		(fp_line
			(start 0.54991 -0.350012)
			(end -0.54991 -0.350012)
			(stroke
				(width 0.1)
				(type default)
			)
			(layer "F.Fab")
		)
		(fp_line
			(start 0.54991 0.350012)
			(end 0.54991 -0.350012)
			(stroke
				(width 0.1)
				(type default)
			)
			(layer "F.Fab")
		)
		(fp_text user "+"
			(at -0.381 -1.30175 180)
			(unlocked yes)
			(layer "F.SilkS")
			(effects
				(font
					(size 1.905 1.4224)
					(thickness 0.1524)
				)
				(justify left)
			)
		)
		(fp_text user "-"
			(at 2.159 0.22225 180)
			(unlocked yes)
			(layer "F.SilkS")
			(effects
				(font
					(size 1.905 1.4224)
					(thickness 0.1524)
				)
				(justify left)
			)
		)
		(fp_text user "+"
			(at -0.808228 0.239014 180)
			(unlocked yes)
			(layer "F.Fab")
			(effects
				(font
					(size 1.905 1.4224)
					(thickness 0.1524)
				)
				(justify left)
			)
		)
		(fp_text user "-"
			(at 2.48539 0.239014 180)
			(unlocked yes)
			(layer "F.Fab")
			(effects
				(font
					(size 1.905 1.4224)
					(thickness 0.1524)
				)
				(justify left)
			)
		)
		(pad "A" smd rect
			(at -0.424942 0)
			(size 0.5588 0.6096)
			(layers "F.Cu" "F.Mask" "F.Paste")
			(net "GND")
		)
		(pad "C" smd rect
			(at 0.424942 0 180)
			(size 0.5588 0.6096)
			(layers "F.Cu" "F.Mask" "F.Paste")
			(net "FAN_1_FAIL_R_LED_N")
		)
	)
	(footprint ""
		(layer "F.Cu")
		(at 42.635932 -72.066912)
		(property "Reference" "R5420"
			(at 0 0 0)
			(layer "F.SilkS")
			(hide yes)
			(effects
				(font
					(size 1.27 1.27)
				)
			)
		)
		(property "Value" ""
			(at 0 0 0)
			(layer "F.Fab")
			(effects
				(font
					(size 1.27 1.27)
				)
			)
		)
		(duplicate_pad_numbers_are_jumpers no)
		(fp_line
			(start -0.7874 -0.4064)
			(end 0.7874 -0.4064)
			(stroke
				(width 0.1524)
				(type default)
			)
			(layer "F.SilkS")
		)
		(fp_line
			(start -0.7874 0.4064)
			(end -0.7874 -0.4064)
			(stroke
				(width 0.1524)
				(type default)
			)
			(layer "F.SilkS")
		)
		(fp_line
			(start 0.7874 -0.4064)
			(end 0.7874 0.4064)
			(stroke
				(width 0.1524)
				(type default)
			)
			(layer "F.SilkS")
		)
		(fp_line
			(start 0.7874 0.4064)
			(end -0.7874 0.4064)
			(stroke
				(width 0.1524)
				(type default)
			)
			(layer "F.SilkS")
		)
		(fp_line
			(start -0.67945 -0.305054)
			(end -0.12065 -0.305054)
			(stroke
				(width 0.1)
				(type default)
			)
			(layer "F.Fab")
		)
		(fp_line
			(start -0.67945 0.3048)
			(end -0.67945 -0.305054)
			(stroke
				(width 0.1)
				(type default)
			)
			(layer "F.Fab")
		)
		(fp_line
			(start -0.12065 -0.305054)
			(end -0.12065 -0.2794)
			(stroke
				(width 0.1)
				(type default)
			)
			(layer "F.Fab")
		)
		(fp_line
			(start -0.12065 -0.2794)
			(end 0.12065 -0.2794)
			(stroke
				(width 0.1)
				(type default)
			)
			(layer "F.Fab")
		)
		(fp_line
			(start -0.12065 0.2794)
			(end -0.12065 0.3048)
			(stroke
				(width 0.1)
				(type default)
			)
			(layer "F.Fab")
		)
		(fp_line
			(start -0.12065 0.3048)
			(end -0.67945 0.3048)
			(stroke
				(width 0.1)
				(type default)
			)
			(layer "F.Fab")
		)
		(fp_line
			(start 0.120396 0.2794)
			(end -0.12065 0.2794)
			(stroke
				(width 0.1)
				(type default)
			)
			(layer "F.Fab")
		)
		(fp_line
			(start 0.120396 0.3048)
			(end 0.120396 0.2794)
			(stroke
				(width 0.1)
				(type default)
			)
			(layer "F.Fab")
		)
		(fp_line
			(start 0.12065 -0.3048)
			(end 0.67945 -0.3048)
			(stroke
				(width 0.1)
				(type default)
			)
			(layer "F.Fab")
		)
		(fp_line
			(start 0.12065 -0.2794)
			(end 0.12065 -0.3048)
			(stroke
				(width 0.1)
				(type default)
			)
			(layer "F.Fab")
		)
		(fp_line
			(start 0.67945 -0.3048)
			(end 0.67945 0.3048)
			(stroke
				(width 0.1)
				(type default)
			)
			(layer "F.Fab")
		)
		(fp_line
			(start 0.67945 0.3048)
			(end 0.120396 0.3048)
			(stroke
				(width 0.1)
				(type default)
			)
			(layer "F.Fab")
		)
		(pad "1" smd circle
			(at -0.40005 0)
			(size 0 0)
			(layers "F.Cu" "F.Mask" "F.Paste")
			(net "FAN_2_PRESENT_R")
		)
		(pad "2" smd circle
			(at 0.40005 0)
			(size 0 0)
			(layers "F.Cu" "F.Mask" "F.Paste")
			(net "FAN_2_PRESENT")
		)
	)
	(footprint ""
		(layer "F.Cu")
		(at 37.338 -298.196)
		(property "Reference" "R5187"
			(at 0 0 0)
			(layer "F.SilkS")
			(hide yes)
			(effects
				(font
					(size 1.27 1.27)
				)
			)
		)
		(property "Value" ""
			(at 0 0 0)
			(layer "F.Fab")
			(effects
				(font
					(size 1.27 1.27)
				)
			)
		)
		(duplicate_pad_numbers_are_jumpers no)
		(fp_line
			(start -0.7874 -0.4064)
			(end 0.7874 -0.4064)
			(stroke
				(width 0.1524)
				(type default)
			)
			(layer "F.SilkS")
		)
		(fp_line
			(start -0.7874 0.4064)
			(end -0.7874 -0.4064)
			(stroke
				(width 0.1524)
				(type default)
			)
			(layer "F.SilkS")
		)
		(fp_line
			(start 0.7874 -0.4064)
			(end 0.7874 0.4064)
			(stroke
				(width 0.1524)
				(type default)
			)
			(layer "F.SilkS")
		)
		(fp_line
			(start 0.7874 0.4064)
			(end -0.7874 0.4064)
			(stroke
				(width 0.1524)
				(type default)
			)
			(layer "F.SilkS")
		)
		(fp_line
			(start -0.67945 -0.305054)
			(end -0.12065 -0.305054)
			(stroke
				(width 0.1)
				(type default)
			)
			(layer "F.Fab")
		)
		(fp_line
			(start -0.67945 0.3048)
			(end -0.67945 -0.305054)
			(stroke
				(width 0.1)
				(type default)
			)
			(layer "F.Fab")
		)
		(fp_line
			(start -0.12065 -0.305054)
			(end -0.12065 -0.2794)
			(stroke
				(width 0.1)
				(type default)
			)
			(layer "F.Fab")
		)
		(fp_line
			(start -0.12065 -0.2794)
			(end 0.12065 -0.2794)
			(stroke
				(width 0.1)
				(type default)
			)
			(layer "F.Fab")
		)
		(fp_line
			(start -0.12065 0.2794)
			(end -0.12065 0.3048)
			(stroke
				(width 0.1)
				(type default)
			)
			(layer "F.Fab")
		)
		(fp_line
			(start -0.12065 0.3048)
			(end -0.67945 0.3048)
			(stroke
				(width 0.1)
				(type default)
			)
			(layer "F.Fab")
		)
		(fp_line
			(start 0.120396 0.2794)
			(end -0.12065 0.2794)
			(stroke
				(width 0.1)
				(type default)
			)
			(layer "F.Fab")
		)
		(fp_line
			(start 0.120396 0.3048)
			(end 0.120396 0.2794)
			(stroke
				(width 0.1)
				(type default)
			)
			(layer "F.Fab")
		)
		(fp_line
			(start 0.12065 -0.3048)
			(end 0.67945 -0.3048)
			(stroke
				(width 0.1)
				(type default)
			)
			(layer "F.Fab")
		)
		(fp_line
			(start 0.12065 -0.2794)
			(end 0.12065 -0.3048)
			(stroke
				(width 0.1)
				(type default)
			)
			(layer "F.Fab")
		)
		(fp_line
			(start 0.67945 -0.3048)
			(end 0.67945 0.3048)
			(stroke
				(width 0.1)
				(type default)
			)
			(layer "F.Fab")
		)
		(fp_line
			(start 0.67945 0.3048)
			(end 0.120396 0.3048)
			(stroke
				(width 0.1)
				(type default)
			)
			(layer "F.Fab")
		)
		(pad "1" smd circle
			(at -0.40005 0)
			(size 0 0)
			(layers "F.Cu" "F.Mask" "F.Paste")
			(net "SMB_FAN0_SCL")
		)
		(pad "2" smd circle
			(at 0.40005 0)
			(size 0 0)
			(layers "F.Cu" "F.Mask" "F.Paste")
			(net "SMB_FAN0_SCL_R")
		)
	)
	(footprint ""
		(layer "F.Cu")
		(at 20.9042 -31.496 90)
		(property "Reference" "C2124"
			(at 0 0 90)
			(layer "F.SilkS")
			(hide yes)
			(effects
				(font
					(size 1.27 1.27)
				)
			)
		)
		(property "Value" ""
			(at 0 0 90)
			(layer "F.Fab")
			(effects
				(font
					(size 1.27 1.27)
				)
			)
		)
		(duplicate_pad_numbers_are_jumpers no)
		(fp_line
			(start 1.2954 -0.5842)
			(end 1.2954 0.5842)
			(stroke
				(width 0.1524)
				(type default)
			)
			(layer "F.SilkS")
		)
		(fp_line
			(start -1.2954 -0.5842)
			(end 1.2954 -0.5842)
			(stroke
				(width 0.1524)
				(type default)
			)
			(layer "F.SilkS")
		)
		(fp_line
			(start 1.2954 0.5842)
			(end -1.2954 0.5842)
			(stroke
				(width 0.1524)
				(type default)
			)
			(layer "F.SilkS")
		)
		(fp_line
			(start -1.2954 0.5842)
			(end -1.2954 -0.5842)
			(stroke
				(width 0.1524)
				(type default)
			)
			(layer "F.SilkS")
		)
		(fp_line
			(start 0.8636 -0.4572)
			(end 0.8636 -0.4064)
			(stroke
				(width 0.1)
				(type default)
			)
			(layer "F.Fab")
		)
		(fp_line
			(start -0.8636 -0.4572)
			(end 0.8636 -0.4572)
			(stroke
				(width 0.1)
				(type default)
			)
			(layer "F.Fab")
		)
		(fp_line
			(start 1.1938 -0.4064)
			(end 1.1938 0.4064)
			(stroke
				(width 0.1)
				(type default)
			)
			(layer "F.Fab")
		)
		(fp_line
			(start 0.8636 -0.4064)
			(end 1.1938 -0.4064)
			(stroke
				(width 0.1)
				(type default)
			)
			(layer "F.Fab")
		)
		(fp_line
			(start -0.8636 -0.4064)
			(end -0.8636 -0.4572)
			(stroke
				(width 0.1)
				(type default)
			)
			(layer "F.Fab")
		)
		(fp_line
			(start -1.1938 -0.4064)
			(end -0.8636 -0.4064)
			(stroke
				(width 0.1)
				(type default)
			)
			(layer "F.Fab")
		)
		(fp_line
			(start 1.1938 0.4064)
			(end 0.8636 0.4064)
			(stroke
				(width 0.1)
				(type default)
			)
			(layer "F.Fab")
		)
		(fp_line
			(start 0.8636 0.4064)
			(end 0.8636 0.4572)
			(stroke
				(width 0.1)
				(type default)
			)
			(layer "F.Fab")
		)
		(fp_line
			(start -0.8636 0.4064)
			(end -1.1938 0.4064)
			(stroke
				(width 0.1)
				(type default)
			)
			(layer "F.Fab")
		)
		(fp_line
			(start -1.1938 0.4064)
			(end -1.1938 -0.4064)
			(stroke
				(width 0.1)
				(type default)
			)
			(layer "F.Fab")
		)
		(fp_line
			(start 0.8636 0.4572)
			(end -0.8636 0.4572)
			(stroke
				(width 0.1)
				(type default)
			)
			(layer "F.Fab")
		)
		(fp_line
			(start -0.8636 0.4572)
			(end -0.8636 0.4064)
			(stroke
				(width 0.1)
				(type default)
			)
			(layer "F.Fab")
		)
		(pad "1" smd rect
			(at -0.7366 0)
			(size 0.7112 0.8128)
			(layers "F.Cu" "F.Mask" "F.Paste")
			(net "U409_D1")
		)
		(pad "2" smd rect
			(at 0.7366 0)
			(size 0.7112 0.8128)
			(layers "F.Cu" "F.Mask" "F.Paste")
			(net "GND")
		)
	)
)
